# BASEBOARD_FAB2 (Tioga Pass) — schematic netlist excerpt (pin names and nets, part order shuffled) for the footprints in the layout excerpt that follows; sources: Cadence DE-HDL packaged netlist, KiCad conversion of Wiwynn_Tioga_Pass_MB.brd

FB7E1  FERRITE  22 FB  pkg SM  page 241 : A = P12V_STBY ; B = VR_FET_SW_P5V_STBY_PVIN
R8B32  RES  10.0K 1% CHIP  pkg 0402  page 115 : A = A_USB2_VBUS ; B = GND
R8C2  RES  4.75K 1% CHIP  pkg 0402  page 133 : A = P3V3_STBY ; B = IRQ_BMC_PCH_SCI_LPC_N

(kicad_pcb
	(version 20260206)
	(generator "pcbnew")
	(generator_version "10.0")
	(general
		(thickness 1.6)
		(legacy_teardrops no)
	)
	(paper "A4")
	(title_block
		(title "Wiwynn_Tioga_Pass_MB.brd")
		(comment 1 "Tioga Pass / footprints 75-77 of 4770")
	)
	(layers
		(0 "F.Cu" signal "TOP")
		(4 "In1.Cu" signal "L2GND")
		(6 "In2.Cu" signal "L3")
		(8 "In3.Cu" signal "L4GND")
		(10 "In4.Cu" signal "L5")
		(12 "In5.Cu" signal "L6GND")
		(14 "In6.Cu" signal "L7VCC")
		(16 "In7.Cu" signal "L8VCC")
		(18 "In8.Cu" signal "L9GND")
		(20 "In9.Cu" signal "L10")
		(22 "In10.Cu" signal "L11GND")
		(24 "In11.Cu" signal "L12")
		(26 "In12.Cu" signal "L13GND")
		(2 "B.Cu" signal "BOTTOM")
		(9 "F.Adhes" user "F.Adhesive")
		(11 "B.Adhes" user "B.Adhesive")
		(13 "F.Paste" user "Package Geometry/Pastemask Top")
		(15 "B.Paste" user "Package Geometry/Pastemask Bottom")
		(5 "F.SilkS" user "Ref Des/Silkscreen Top")
		(7 "B.SilkS" user "Ref Des/Silkscreen Bottom")
		(1 "F.Mask" user "Board Geometry/Soldermask Top")
		(3 "B.Mask" user "Board Geometry/Soldermask Bottom")
		(17 "Dwgs.User" user "User.Drawings")
		(19 "Cmts.User" user "User.Comments")
		(21 "Eco1.User" user "User.Eco1")
		(23 "Eco2.User" user "User.Eco2")
		(25 "Edge.Cuts" user "Board Geometry/Outline")
		(27 "Margin" user)
		(31 "F.CrtYd" user "Package Geometry/Place Bound Top")
		(29 "B.CrtYd" user "Package Geometry/Place Bound Bottom")
		(35 "F.Fab" user "Ref Des/Assembly Top")
		(33 "B.Fab" user "Ref Des/Assembly Bottom")
	)
	(footprint ""
		(layer "F.Cu")
		(at 403.86 -123.7742 90)
		(property "Reference" "R8B32"
			(at 0 0 90)
			(layer "F.SilkS")
			(hide yes)
			(effects
				(font
					(size 1.27 1.27)
				)
			)
		)
		(property "Value" ""
			(at 0 0 90)
			(layer "F.Fab")
			(effects
				(font
					(size 1.27 1.27)
				)
			)
		)
		(duplicate_pad_numbers_are_jumpers no)
		(fp_poly
			(pts
				(xy -0.2794 -0.1016) (xy 0.2794 -0.1016) (xy 0.2794 0.9906) (xy -0.2794 0.9906)
			)
			(stroke
				(width 0)
				(type default)
			)
			(fill no)
			(layer "F.CrtYd")
		)
		(fp_line
			(start 0.2794 -0.1016)
			(end -0.2794 -0.1016)
			(stroke
				(width 0.1)
				(type default)
			)
			(layer "F.Fab")
		)
		(fp_line
			(start -0.2794 -0.1016)
			(end -0.2794 0.9906)
			(stroke
				(width 0.1)
				(type default)
			)
			(layer "F.Fab")
		)
		(fp_line
			(start 0.2794 0.9906)
			(end 0.2794 -0.1016)
			(stroke
				(width 0.1)
				(type default)
			)
			(layer "F.Fab")
		)
		(fp_line
			(start -0.2794 0.9906)
			(end 0.2794 0.9906)
			(stroke
				(width 0.1)
				(type default)
			)
			(layer "F.Fab")
		)
		(pad "1" smd rect
			(at 0 0 90)
			(size 0.508 0.508)
			(layers "F.Cu" "F.Mask" "F.Paste")
			(net "A_USB2_VBUS")
		)
		(pad "2" smd rect
			(at 0 0.889 90)
			(size 0.508 0.508)
			(layers "F.Cu" "F.Mask" "F.Paste")
			(net "GND")
		)
		(zone
			(layer "F.Cu")
			(hatch none 0.5)
			(connect_pads
				(clearance 0)
			)
			(min_thickness 0.25)
			(keepout
				(tracks allowed)
				(vias not_allowed)
				(pads allowed)
				(copperpour not_allowed)
				(footprints allowed)
			)
			(placement
				(enabled no)
				(sheetname "")
			)
			(fill
				(thermal_gap 0.5)
				(thermal_bridge_width 0.5)
				(island_removal_mode 0)
			)
			(polygon
				(pts
					(xy 404.114 -123.5202) (xy 404.114 -124.0282) (xy 404.495 -124.0282) (xy 404.495 -123.5202)
				)
			)
		)
		(zone
			(layer "F.Cu")
			(hatch none 0.5)
			(connect_pads
				(clearance 0)
			)
			(min_thickness 0.25)
			(keepout
				(tracks not_allowed)
				(vias allowed)
				(pads allowed)
				(copperpour not_allowed)
				(footprints allowed)
			)
			(placement
				(enabled no)
				(sheetname "")
			)
			(fill
				(thermal_gap 0.5)
				(thermal_bridge_width 0.5)
				(island_removal_mode 0)
			)
			(polygon
				(pts
					(xy 404.495 -123.5202) (xy 404.495 -124.0282) (xy 404.114 -124.0282) (xy 404.114 -123.5202)
				)
			)
		)
	)
	(footprint ""
		(layer "F.Cu")
		(at 384.048 -64.2874 180)
		(property "Reference" "FB7E1"
			(at -1.48717 0.635 270)
			(unlocked yes)
			(layer "F.SilkS")
			(effects
				(font
					(size 0.7874 0.5842)
					(thickness 0.1524)
				)
			)
		)
		(property "Value" ""
			(at 0 0 180)
			(layer "F.Fab")
			(effects
				(font
					(size 1.27 1.27)
				)
			)
		)
		(duplicate_pad_numbers_are_jumpers no)
		(fp_poly
			(pts
				(xy -0.7239 -0.26035) (xy 0.7239 -0.26035) (xy 0.7239 2.03835) (xy -0.7239 2.03835)
			)
			(stroke
				(width 0)
				(type default)
			)
			(fill no)
			(layer "F.CrtYd")
		)
		(fp_line
			(start 0.7239 2.03835)
			(end -0.7239 2.03835)
			(stroke
				(width 0.1)
				(type default)
			)
			(layer "F.Fab")
		)
		(fp_line
			(start 0.7239 -0.26035)
			(end 0.7239 2.03835)
			(stroke
				(width 0.1)
				(type default)
			)
			(layer "F.Fab")
		)
		(fp_line
			(start -0.7239 2.03835)
			(end -0.7239 -0.26035)
			(stroke
				(width 0.1)
				(type default)
			)
			(layer "F.Fab")
		)
		(fp_line
			(start -0.7239 -0.26035)
			(end 0.7239 -0.26035)
			(stroke
				(width 0.1)
				(type default)
			)
			(layer "F.Fab")
		)
		(pad "1" smd rect
			(at 0 0 180)
			(size 1.27 1.016)
			(layers "F.Cu" "F.Mask" "F.Paste")
			(net "P12V_STBY")
		)
		(pad "2" smd rect
			(at 0 1.778 180)
			(size 1.27 1.016)
			(layers "F.Cu" "F.Mask" "F.Paste")
			(net "VR_FET_SW_P5V_STBY_PVIN")
		)
		(zone
			(layer "F.Cu")
			(hatch none 0.5)
			(connect_pads
				(clearance 0)
			)
			(min_thickness 0.25)
			(keepout
				(tracks not_allowed)
				(vias allowed)
				(pads allowed)
				(copperpour not_allowed)
				(footprints allowed)
			)
			(placement
				(enabled no)
				(sheetname "")
			)
			(fill
				(thermal_gap 0.5)
				(thermal_bridge_width 0.5)
				(island_removal_mode 0)
			)
			(polygon
				(pts
					(xy 383.413 -64.7954) (xy 383.413 -65.5574) (xy 383.5019 -65.5574) (xy 384.683 -65.5574) (xy 384.683 -64.7954)
				)
			)
		)
	)
	(footprint ""
		(layer "F.Cu")
		(at 411.0355 -112.395 -90)
		(property "Reference" "R8C2"
			(at 0 0 270)
			(layer "F.SilkS")
			(hide yes)
			(effects
				(font
					(size 1.27 1.27)
				)
			)
		)
		(property "Value" ""
			(at 0 0 270)
			(layer "F.Fab")
			(effects
				(font
					(size 1.27 1.27)
				)
			)
		)
		(duplicate_pad_numbers_are_jumpers no)
		(fp_poly
			(pts
				(xy -0.2794 -0.1016) (xy 0.2794 -0.1016) (xy 0.2794 0.9906) (xy -0.2794 0.9906)
			)
			(stroke
				(width 0)
				(type default)
			)
			(fill no)
			(layer "F.CrtYd")
		)
		(fp_line
			(start -0.2794 0.9906)
			(end 0.2794 0.9906)
			(stroke
				(width 0.1)
				(type default)
			)
			(layer "F.Fab")
		)
		(fp_line
			(start 0.2794 0.9906)
			(end 0.2794 -0.1016)
			(stroke
				(width 0.1)
				(type default)
			)
			(layer "F.Fab")
		)
		(fp_line
			(start -0.2794 -0.1016)
			(end -0.2794 0.9906)
			(stroke
				(width 0.1)
				(type default)
			)
			(layer "F.Fab")
		)
		(fp_line
			(start 0.2794 -0.1016)
			(end -0.2794 -0.1016)
			(stroke
				(width 0.1)
				(type default)
			)
			(layer "F.Fab")
		)
		(pad "1" smd rect
			(at 0 0 270)
			(size 0.508 0.508)
			(layers "F.Cu" "F.Mask" "F.Paste")
			(net "P3V3_STBY")
		)
		(pad "2" smd rect
			(at 0 0.889 270)
			(size 0.508 0.508)
			(layers "F.Cu" "F.Mask" "F.Paste")
			(net "IRQ_BMC_PCH_SCI_LPC_N")
		)
		(zone
			(layer "F.Cu")
			(hatch none 0.5)
			(connect_pads
				(clearance 0)
			)
			(min_thickness 0.25)
			(keepout
				(tracks not_allowed)
				(vias allowed)
				(pads allowed)
				(copperpour not_allowed)
				(footprints allowed)
			)
			(placement
				(enabled no)
				(sheetname "")
			)
			(fill
				(thermal_gap 0.5)
				(thermal_bridge_width 0.5)
				(island_removal_mode 0)
			)
			(polygon
				(pts
					(xy 410.4005 -112.649) (xy 410.4005 -112.141) (xy 410.7815 -112.141) (xy 410.7815 -112.649)
				)
			)
		)
		(zone
			(layer "F.Cu")
			(hatch none 0.5)
			(connect_pads
				(clearance 0)
			)
			(min_thickness 0.25)
			(keepout
				(tracks allowed)
				(vias not_allowed)
				(pads allowed)
				(copperpour not_allowed)
				(footprints allowed)
			)
			(placement
				(enabled no)
				(sheetname "")
			)
			(fill
				(thermal_gap 0.5)
				(thermal_bridge_width 0.5)
				(island_removal_mode 0)
			)
			(polygon
				(pts
					(xy 410.7815 -112.649) (xy 410.7815 -112.141) (xy 410.4005 -112.141) (xy 410.4005 -112.649)
				)
			)
		)
	)
)
